(kicad_pcb
	(version 20260206)
	(generator "pcbnew")
	(generator_version "10.0")
	(general
		(thickness 1.6)
		(legacy_teardrops no)
	)
	(paper "A4")
	(title_block
		(title "04192023_DAF0TMB3IC0_F0TG_MB_C_brd_V02_OCP.brd")
		(comment 1 "Grand Teton / footprints 4583-4588 of 8354")
	)
	(layers
		(0 "F.Cu" signal "TOP")
		(4 "In1.Cu" signal "GND")
		(6 "In2.Cu" signal "IN1")
		(8 "In3.Cu" signal "GND1")
		(10 "In4.Cu" signal "IN2")
		(12 "In5.Cu" signal "GND2")
		(14 "In6.Cu" signal "IN3")
		(16 "In7.Cu" signal "GND3")
		(18 "In8.Cu" signal "VCC")
		(20 "In9.Cu" signal "VCC1")
		(22 "In10.Cu" signal "GND4")
		(24 "In11.Cu" signal "IN4")
		(26 "In12.Cu" signal "GND5")
		(28 "In13.Cu" signal "IN5")
		(30 "In14.Cu" signal "GND6")
		(32 "In15.Cu" signal "IN6")
		(34 "In16.Cu" signal "GND7")
		(2 "B.Cu" signal "BOTTOM")
		(9 "F.Adhes" user "F.Adhesive")
		(11 "B.Adhes" user "B.Adhesive")
		(13 "F.Paste" user "Package Geometry/Pastemask Top")
		(15 "B.Paste" user "Package Geometry/Pastemask Bottom")
		(5 "F.SilkS" user "Ref Des/Silkscreen Top")
		(7 "B.SilkS" user "Ref Des/Silkscreen Bottom")
		(1 "F.Mask" user "Board Geometry/Soldermask Top")
		(3 "B.Mask" user "Board Geometry/Soldermask Bottom")
		(17 "Dwgs.User" user "User.Drawings")
		(19 "Cmts.User" user "User.Comments")
		(21 "Eco1.User" user "User.Eco1")
		(23 "Eco2.User" user "User.Eco2")
		(25 "Edge.Cuts" user "Board Geometry/Outline")
		(27 "Margin" user)
		(31 "F.CrtYd" user "Package Geometry/Place Bound Top")
		(29 "B.CrtYd" user "Package Geometry/Place Bound Bottom")
		(35 "F.Fab" user "Ref Des/Assembly Top")
		(33 "B.Fab" user "Ref Des/Assembly Bottom")
	)
	(footprint ""
		(layer "F.Cu")
		(at 213.106 -98.425 90)
		(property "Reference" "R9030"
			(at 0 0 90)
			(layer "F.SilkS")
			(hide yes)
			(effects
				(font
					(size 1.27 1.27)
				)
			)
		)
		(property "Value" ""
			(at 0 0 90)
			(layer "F.Fab")
			(effects
				(font
					(size 1.27 1.27)
				)
			)
		)
		(duplicate_pad_numbers_are_jumpers no)
		(fp_line
			(start 0.7874 -0.4064)
			(end 0.7874 0.4064)
			(stroke
				(width 0.1524)
				(type default)
			)
			(layer "F.SilkS")
		)
		(fp_line
			(start -0.7874 -0.4064)
			(end 0.7874 -0.4064)
			(stroke
				(width 0.1524)
				(type default)
			)
			(layer "F.SilkS")
		)
		(fp_line
			(start 0.7874 0.4064)
			(end -0.7874 0.4064)
			(stroke
				(width 0.1524)
				(type default)
			)
			(layer "F.SilkS")
		)
		(fp_line
			(start -0.7874 0.4064)
			(end -0.7874 -0.4064)
			(stroke
				(width 0.1524)
				(type default)
			)
			(layer "F.SilkS")
		)
		(fp_line
			(start -0.12065 -0.305054)
			(end -0.12065 -0.2794)
			(stroke
				(width 0.1)
				(type default)
			)
			(layer "F.Fab")
		)
		(fp_line
			(start -0.67945 -0.305054)
			(end -0.12065 -0.305054)
			(stroke
				(width 0.1)
				(type default)
			)
			(layer "F.Fab")
		)
		(fp_line
			(start 0.67945 -0.3048)
			(end 0.67945 0.3048)
			(stroke
				(width 0.1)
				(type default)
			)
			(layer "F.Fab")
		)
		(fp_line
			(start 0.12065 -0.3048)
			(end 0.67945 -0.3048)
			(stroke
				(width 0.1)
				(type default)
			)
			(layer "F.Fab")
		)
		(fp_line
			(start 0.12065 -0.2794)
			(end 0.12065 -0.3048)
			(stroke
				(width 0.1)
				(type default)
			)
			(layer "F.Fab")
		)
		(fp_line
			(start -0.12065 -0.2794)
			(end 0.12065 -0.2794)
			(stroke
				(width 0.1)
				(type default)
			)
			(layer "F.Fab")
		)
		(fp_line
			(start 0.120396 0.2794)
			(end -0.12065 0.2794)
			(stroke
				(width 0.1)
				(type default)
			)
			(layer "F.Fab")
		)
		(fp_line
			(start -0.12065 0.2794)
			(end -0.12065 0.3048)
			(stroke
				(width 0.1)
				(type default)
			)
			(layer "F.Fab")
		)
		(fp_line
			(start 0.67945 0.3048)
			(end 0.120396 0.3048)
			(stroke
				(width 0.1)
				(type default)
			)
			(layer "F.Fab")
		)
		(fp_line
			(start 0.120396 0.3048)
			(end 0.120396 0.2794)
			(stroke
				(width 0.1)
				(type default)
			)
			(layer "F.Fab")
		)
		(fp_line
			(start -0.12065 0.3048)
			(end -0.67945 0.3048)
			(stroke
				(width 0.1)
				(type default)
			)
			(layer "F.Fab")
		)
		(fp_line
			(start -0.67945 0.3048)
			(end -0.67945 -0.305054)
			(stroke
				(width 0.1)
				(type default)
			)
			(layer "F.Fab")
		)
		(pad "1" smd circle
			(at -0.40005 0 90)
			(size 0 0)
			(layers "F.Cu" "F.Mask" "F.Paste")
			(net "OCP_SFF_AUX_PWR_EN_R3")
		)
		(pad "2" smd circle
			(at 0.40005 0 90)
			(size 0 0)
			(layers "F.Cu" "F.Mask" "F.Paste")
			(net "FM_PLD_OCP_SFF_AUX_PWR_EN")
		)
	)
	(footprint ""
		(layer "F.Cu")
		(at 12.777216 -15.32128 90)
		(property "Reference" "R3177"
			(at 0 0 90)
			(layer "F.SilkS")
			(hide yes)
			(effects
				(font
					(size 1.27 1.27)
				)
			)
		)
		(property "Value" ""
			(at 0 0 90)
			(layer "F.Fab")
			(effects
				(font
					(size 1.27 1.27)
				)
			)
		)
		(duplicate_pad_numbers_are_jumpers no)
		(fp_line
			(start 0.7874 -0.4064)
			(end 0.7874 0.4064)
			(stroke
				(width 0.1524)
				(type default)
			)
			(layer "F.SilkS")
		)
		(fp_line
			(start -0.7874 -0.4064)
			(end 0.7874 -0.4064)
			(stroke
				(width 0.1524)
				(type default)
			)
			(layer "F.SilkS")
		)
		(fp_line
			(start 0.7874 0.4064)
			(end -0.7874 0.4064)
			(stroke
				(width 0.1524)
				(type default)
			)
			(layer "F.SilkS")
		)
		(fp_line
			(start -0.7874 0.4064)
			(end -0.7874 -0.4064)
			(stroke
				(width 0.1524)
				(type default)
			)
			(layer "F.SilkS")
		)
		(fp_line
			(start -0.12065 -0.305054)
			(end -0.12065 -0.2794)
			(stroke
				(width 0.1)
				(type default)
			)
			(layer "F.Fab")
		)
		(fp_line
			(start -0.67945 -0.305054)
			(end -0.12065 -0.305054)
			(stroke
				(width 0.1)
				(type default)
			)
			(layer "F.Fab")
		)
		(fp_line
			(start 0.67945 -0.3048)
			(end 0.67945 0.3048)
			(stroke
				(width 0.1)
				(type default)
			)
			(layer "F.Fab")
		)
		(fp_line
			(start 0.12065 -0.3048)
			(end 0.67945 -0.3048)
			(stroke
				(width 0.1)
				(type default)
			)
			(layer "F.Fab")
		)
		(fp_line
			(start 0.12065 -0.2794)
			(end 0.12065 -0.3048)
			(stroke
				(width 0.1)
				(type default)
			)
			(layer "F.Fab")
		)
		(fp_line
			(start -0.12065 -0.2794)
			(end 0.12065 -0.2794)
			(stroke
				(width 0.1)
				(type default)
			)
			(layer "F.Fab")
		)
		(fp_line
			(start 0.120396 0.2794)
			(end -0.12065 0.2794)
			(stroke
				(width 0.1)
				(type default)
			)
			(layer "F.Fab")
		)
		(fp_line
			(start -0.12065 0.2794)
			(end -0.12065 0.3048)
			(stroke
				(width 0.1)
				(type default)
			)
			(layer "F.Fab")
		)
		(fp_line
			(start 0.67945 0.3048)
			(end 0.120396 0.3048)
			(stroke
				(width 0.1)
				(type default)
			)
			(layer "F.Fab")
		)
		(fp_line
			(start 0.120396 0.3048)
			(end 0.120396 0.2794)
			(stroke
				(width 0.1)
				(type default)
			)
			(layer "F.Fab")
		)
		(fp_line
			(start -0.12065 0.3048)
			(end -0.67945 0.3048)
			(stroke
				(width 0.1)
				(type default)
			)
			(layer "F.Fab")
		)
		(fp_line
			(start -0.67945 0.3048)
			(end -0.67945 -0.305054)
			(stroke
				(width 0.1)
				(type default)
			)
			(layer "F.Fab")
		)
		(pad "1" smd circle
			(at -0.40005 0 90)
			(size 0 0)
			(layers "F.Cu" "F.Mask" "F.Paste")
			(net "USB2_P10_DN")
		)
		(pad "2" smd circle
			(at 0.40005 0 90)
			(size 0 0)
			(layers "F.Cu" "F.Mask" "F.Paste")
			(net "USB2_CPU0_P10_DN")
		)
	)
	(footprint ""
		(layer "F.Cu")
		(at 99.650296 -417.725098 90)
		(property "Reference" "U272"
			(at 1.712976 -3.64998 90)
			(unlocked yes)
			(layer "F.SilkS")
			(effects
				(font
					(size 0.7874 0.5842)
					(thickness 0.1524)
				)
				(justify left)
			)
		)
		(property "Value" ""
			(at 0 0 90)
			(layer "F.Fab")
			(effects
				(font
					(size 1.27 1.27)
				)
			)
		)
		(duplicate_pad_numbers_are_jumpers no)
		(fp_line
			(start 3.447796 -2.500122)
			(end 1.484122 -2.500122)
			(stroke
				(width 0.1524)
				(type default)
			)
			(layer "F.SilkS")
		)
		(fp_line
			(start 1.484122 -2.500122)
			(end 0 -1.016)
			(stroke
				(width 0.1524)
				(type default)
			)
			(layer "F.SilkS")
		)
		(fp_line
			(start -1.484122 -2.500122)
			(end -3.447796 -2.500122)
			(stroke
				(width 0.1524)
				(type default)
			)
			(layer "F.SilkS")
		)
		(fp_line
			(start -3.447796 -2.500122)
			(end -3.447796 2.500122)
			(stroke
				(width 0.1524)
				(type default)
			)
			(layer "F.SilkS")
		)
		(fp_line
			(start 0 -1.016)
			(end -1.484122 -2.500122)
			(stroke
				(width 0.1524)
				(type default)
			)
			(layer "F.SilkS")
		)
		(fp_line
			(start 3.447796 2.500122)
			(end 3.447796 -2.500122)
			(stroke
				(width 0.1524)
				(type default)
			)
			(layer "F.SilkS")
		)
		(fp_line
			(start -3.447796 2.500122)
			(end 3.447796 2.500122)
			(stroke
				(width 0.1524)
				(type default)
			)
			(layer "F.SilkS")
		)
		(fp_poly
			(pts
				(xy -2.37871 -3.737102) (xy -3.39471 -3.737102) (xy -2.88671 -2.721102)
			)
			(stroke
				(width 0)
				(type default)
			)
			(fill yes)
			(layer "F.SilkS")
		)
		(fp_line
			(start 1.999996 -2.500122)
			(end -1.999996 -2.500122)
			(stroke
				(width 0.1)
				(type default)
			)
			(layer "F.Fab")
		)
		(fp_line
			(start -1.999996 -2.500122)
			(end -1.999996 2.500122)
			(stroke
				(width 0.1)
				(type default)
			)
			(layer "F.Fab")
		)
		(fp_line
			(start 1.999996 2.500122)
			(end 1.999996 -2.500122)
			(stroke
				(width 0.1)
				(type default)
			)
			(layer "F.Fab")
		)
		(fp_line
			(start -1.999996 2.500122)
			(end 1.999996 2.500122)
			(stroke
				(width 0.1)
				(type default)
			)
			(layer "F.Fab")
		)
		(fp_poly
			(pts
				(xy -4.5974 -2.413) (xy -4.5974 -1.397) (xy -3.5814 -1.905)
			)
			(stroke
				(width 0)
				(type default)
			)
			(fill yes)
			(layer "F.Fab")
		)
		(pad "1" smd rect
			(at -2.649982 -1.905)
			(size 0.6096 1.3208)
			(layers "F.Cu" "F.Mask" "F.Paste")
			(net "SMB_LM75_2_3V3AUX_SDA_R1")
		)
		(pad "2" smd rect
			(at -2.649982 -0.635)
			(size 0.6096 1.3208)
			(layers "F.Cu" "F.Mask" "F.Paste")
			(net "SMB_LM75_2_3V3AUX_SCL_R1")
		)
		(pad "3" smd rect
			(at -2.649982 0.635)
			(size 0.6096 1.3208)
			(layers "F.Cu" "F.Mask" "F.Paste")
			(net "FM_LM75_2_ALERT_N")
		)
		(pad "4" smd rect
			(at -2.649982 1.905)
			(size 0.6096 1.3208)
			(layers "F.Cu" "F.Mask" "F.Paste")
			(net "GND")
		)
		(pad "5" smd rect
			(at 2.649982 1.905)
			(size 0.6096 1.3208)
			(layers "F.Cu" "F.Mask" "F.Paste")
			(net "U272_2_ADD2")
		)
		(pad "6" smd rect
			(at 2.649982 0.635)
			(size 0.6096 1.3208)
			(layers "F.Cu" "F.Mask" "F.Paste")
			(net "U272_2_ADD1")
		)
		(pad "7" smd rect
			(at 2.649982 -0.635)
			(size 0.6096 1.3208)
			(layers "F.Cu" "F.Mask" "F.Paste")
			(net "U272_2_ADD0")
		)
		(pad "8" smd rect
			(at 2.649982 -1.905)
			(size 0.6096 1.3208)
			(layers "F.Cu" "F.Mask" "F.Paste")
			(net "P3V3_AUX")
		)
	)
	(footprint ""
		(layer "F.Cu")
		(at 21.712682 -422.437052)
		(property "Reference" "C6012"
			(at 0 0 0)
			(layer "F.SilkS")
			(hide yes)
			(effects
				(font
					(size 1.27 1.27)
				)
			)
		)
		(property "Value" ""
			(at 0 0 0)
			(layer "F.Fab")
			(effects
				(font
					(size 1.27 1.27)
				)
			)
		)
		(duplicate_pad_numbers_are_jumpers no)
		(fp_line
			(start -0.7874 -0.4064)
			(end 0.7874 -0.4064)
			(stroke
				(width 0.1524)
				(type default)
			)
			(layer "F.SilkS")
		)
		(fp_line
			(start -0.7874 0.4064)
			(end -0.7874 -0.4064)
			(stroke
				(width 0.1524)
				(type default)
			)
			(layer "F.SilkS")
		)
		(fp_line
			(start 0.7874 -0.4064)
			(end 0.7874 0.4064)
			(stroke
				(width 0.1524)
				(type default)
			)
			(layer "F.SilkS")
		)
		(fp_line
			(start 0.7874 0.4064)
			(end -0.7874 0.4064)
			(stroke
				(width 0.1524)
				(type default)
			)
			(layer "F.SilkS")
		)
		(fp_line
			(start -0.67945 -0.305054)
			(end -0.12065 -0.305054)
			(stroke
				(width 0.1)
				(type default)
			)
			(layer "F.Fab")
		)
		(fp_line
			(start -0.67945 0.3048)
			(end -0.67945 -0.305054)
			(stroke
				(width 0.1)
				(type default)
			)
			(layer "F.Fab")
		)
		(fp_line
			(start -0.12065 -0.305054)
			(end -0.12065 -0.2794)
			(stroke
				(width 0.1)
				(type default)
			)
			(layer "F.Fab")
		)
		(fp_line
			(start -0.12065 -0.2794)
			(end 0.12065 -0.2794)
			(stroke
				(width 0.1)
				(type default)
			)
			(layer "F.Fab")
		)
		(fp_line
			(start -0.12065 0.2794)
			(end -0.12065 0.3048)
			(stroke
				(width 0.1)
				(type default)
			)
			(layer "F.Fab")
		)
		(fp_line
			(start -0.12065 0.3048)
			(end -0.67945 0.3048)
			(stroke
				(width 0.1)
				(type default)
			)
			(layer "F.Fab")
		)
		(fp_line
			(start 0.120396 0.2794)
			(end -0.12065 0.2794)
			(stroke
				(width 0.1)
				(type default)
			)
			(layer "F.Fab")
		)
		(fp_line
			(start 0.120396 0.3048)
			(end 0.120396 0.2794)
			(stroke
				(width 0.1)
				(type default)
			)
			(layer "F.Fab")
		)
		(fp_line
			(start 0.12065 -0.3048)
			(end 0.67945 -0.3048)
			(stroke
				(width 0.1)
				(type default)
			)
			(layer "F.Fab")
		)
		(fp_line
			(start 0.12065 -0.2794)
			(end 0.12065 -0.3048)
			(stroke
				(width 0.1)
				(type default)
			)
			(layer "F.Fab")
		)
		(fp_line
			(start 0.67945 -0.3048)
			(end 0.67945 0.3048)
			(stroke
				(width 0.1)
				(type default)
			)
			(layer "F.Fab")
		)
		(fp_line
			(start 0.67945 0.3048)
			(end 0.120396 0.3048)
			(stroke
				(width 0.1)
				(type default)
			)
			(layer "F.Fab")
		)
		(pad "1" smd circle
			(at -0.40005 0)
			(size 0 0)
			(layers "F.Cu" "F.Mask" "F.Paste")
			(net "BUF2_VDD")
		)
		(pad "2" smd circle
			(at 0.40005 0)
			(size 0 0)
			(layers "F.Cu" "F.Mask" "F.Paste")
			(net "GND")
		)
	)
	(footprint ""
		(layer "F.Cu")
		(at 179.244752 -418.831268 -90)
		(property "Reference" "R9008"
			(at 0 0 270)
			(layer "F.SilkS")
			(hide yes)
			(effects
				(font
					(size 1.27 1.27)
				)
			)
		)
		(property "Value" ""
			(at 0 0 270)
			(layer "F.Fab")
			(effects
				(font
					(size 1.27 1.27)
				)
			)
		)
		(duplicate_pad_numbers_are_jumpers no)
		(fp_line
			(start -0.7874 0.4064)
			(end -0.7874 -0.4064)
			(stroke
				(width 0.1524)
				(type default)
			)
			(layer "F.SilkS")
		)
		(fp_line
			(start 0.7874 0.4064)
			(end -0.7874 0.4064)
			(stroke
				(width 0.1524)
				(type default)
			)
			(layer "F.SilkS")
		)
		(fp_line
			(start -0.7874 -0.4064)
			(end 0.7874 -0.4064)
			(stroke
				(width 0.1524)
				(type default)
			)
			(layer "F.SilkS")
		)
		(fp_line
			(start 0.7874 -0.4064)
			(end 0.7874 0.4064)
			(stroke
				(width 0.1524)
				(type default)
			)
			(layer "F.SilkS")
		)
		(fp_line
			(start -0.67945 0.3048)
			(end -0.67945 -0.305054)
			(stroke
				(width 0.1)
				(type default)
			)
			(layer "F.Fab")
		)
		(fp_line
			(start -0.12065 0.3048)
			(end -0.67945 0.3048)
			(stroke
				(width 0.1)
				(type default)
			)
			(layer "F.Fab")
		)
		(fp_line
			(start 0.120396 0.3048)
			(end 0.120396 0.2794)
			(stroke
				(width 0.1)
				(type default)
			)
			(layer "F.Fab")
		)
		(fp_line
			(start 0.67945 0.3048)
			(end 0.120396 0.3048)
			(stroke
				(width 0.1)
				(type default)
			)
			(layer "F.Fab")
		)
		(fp_line
			(start -0.12065 0.2794)
			(end -0.12065 0.3048)
			(stroke
				(width 0.1)
				(type default)
			)
			(layer "F.Fab")
		)
		(fp_line
			(start 0.120396 0.2794)
			(end -0.12065 0.2794)
			(stroke
				(width 0.1)
				(type default)
			)
			(layer "F.Fab")
		)
		(fp_line
			(start -0.12065 -0.2794)
			(end 0.12065 -0.2794)
			(stroke
				(width 0.1)
				(type default)
			)
			(layer "F.Fab")
		)
		(fp_line
			(start 0.12065 -0.2794)
			(end 0.12065 -0.3048)
			(stroke
				(width 0.1)
				(type default)
			)
			(layer "F.Fab")
		)
		(fp_line
			(start 0.12065 -0.3048)
			(end 0.67945 -0.3048)
			(stroke
				(width 0.1)
				(type default)
			)
			(layer "F.Fab")
		)
		(fp_line
			(start 0.67945 -0.3048)
			(end 0.67945 0.3048)
			(stroke
				(width 0.1)
				(type default)
			)
			(layer "F.Fab")
		)
		(fp_line
			(start -0.67945 -0.305054)
			(end -0.12065 -0.305054)
			(stroke
				(width 0.1)
				(type default)
			)
			(layer "F.Fab")
		)
		(fp_line
			(start -0.12065 -0.305054)
			(end -0.12065 -0.2794)
			(stroke
				(width 0.1)
				(type default)
			)
			(layer "F.Fab")
		)
		(pad "1" smd circle
			(at -0.40005 0 270)
			(size 0 0)
			(layers "F.Cu" "F.Mask" "F.Paste")
			(net "P3V3_AUX")
		)
		(pad "2" smd circle
			(at 0.40005 0 270)
			(size 0 0)
			(layers "F.Cu" "F.Mask" "F.Paste")
			(net "PRSNT_CABLE_SWB_B2")
		)
	)
	(footprint ""
		(layer "F.Cu")
		(at 112.427004 -261.748016 -90)
		(property "Reference" "C2499"
			(at 0 0 270)
			(layer "F.SilkS")
			(hide yes)
			(effects
				(font
					(size 1.27 1.27)
				)
			)
		)
		(property "Value" ""
			(at 0 0 270)
			(layer "F.Fab")
			(effects
				(font
					(size 1.27 1.27)
				)
			)
		)
		(duplicate_pad_numbers_are_jumpers no)
		(fp_line
			(start -0.7874 0.4064)
			(end -0.7874 -0.4064)
			(stroke
				(width 0.1524)
				(type default)
			)
			(layer "F.SilkS")
		)
		(fp_line
			(start 0.7874 0.4064)
			(end -0.7874 0.4064)
			(stroke
				(width 0.1524)
				(type default)
			)
			(layer "F.SilkS")
		)
		(fp_line
			(start -0.7874 -0.4064)
			(end 0.7874 -0.4064)
			(stroke
				(width 0.1524)
				(type default)
			)
			(layer "F.SilkS")
		)
		(fp_line
			(start 0.7874 -0.4064)
			(end 0.7874 0.4064)
			(stroke
				(width 0.1524)
				(type default)
			)
			(layer "F.SilkS")
		)
		(fp_line
			(start -0.67945 0.3048)
			(end -0.67945 -0.305054)
			(stroke
				(width 0.1)
				(type default)
			)
			(layer "F.Fab")
		)
		(fp_line
			(start -0.12065 0.3048)
			(end -0.67945 0.3048)
			(stroke
				(width 0.1)
				(type default)
			)
			(layer "F.Fab")
		)
		(fp_line
			(start 0.120396 0.3048)
			(end 0.120396 0.2794)
			(stroke
				(width 0.1)
				(type default)
			)
			(layer "F.Fab")
		)
		(fp_line
			(start 0.67945 0.3048)
			(end 0.120396 0.3048)
			(stroke
				(width 0.1)
				(type default)
			)
			(layer "F.Fab")
		)
		(fp_line
			(start -0.12065 0.2794)
			(end -0.12065 0.3048)
			(stroke
				(width 0.1)
				(type default)
			)
			(layer "F.Fab")
		)
		(fp_line
			(start 0.120396 0.2794)
			(end -0.12065 0.2794)
			(stroke
				(width 0.1)
				(type default)
			)
			(layer "F.Fab")
		)
		(fp_line
			(start -0.12065 -0.2794)
			(end 0.12065 -0.2794)
			(stroke
				(width 0.1)
				(type default)
			)
			(layer "F.Fab")
		)
		(fp_line
			(start 0.12065 -0.2794)
			(end 0.12065 -0.3048)
			(stroke
				(width 0.1)
				(type default)
			)
			(layer "F.Fab")
		)
		(fp_line
			(start 0.12065 -0.3048)
			(end 0.67945 -0.3048)
			(stroke
				(width 0.1)
				(type default)
			)
			(layer "F.Fab")
		)
		(fp_line
			(start 0.67945 -0.3048)
			(end 0.67945 0.3048)
			(stroke
				(width 0.1)
				(type default)
			)
			(layer "F.Fab")
		)
		(fp_line
			(start -0.67945 -0.305054)
			(end -0.12065 -0.305054)
			(stroke
				(width 0.1)
				(type default)
			)
			(layer "F.Fab")
		)
		(fp_line
			(start -0.12065 -0.305054)
			(end -0.12065 -0.2794)
			(stroke
				(width 0.1)
				(type default)
			)
			(layer "F.Fab")
		)
		(pad "1" smd circle
			(at -0.40005 0 270)
			(size 0 0)
			(layers "F.Cu" "F.Mask" "F.Paste")
			(net "PVDD11_S3_P1")
		)
		(pad "2" smd circle
			(at 0.40005 0 270)
			(size 0 0)
			(layers "F.Cu" "F.Mask" "F.Paste")
			(net "GND")
		)
	)
)
